(kicad_pcb
	(version 20260206)
	(generator "pcbnew")
	(generator_version "10.0")
	(general
		(thickness 1.6)
		(legacy_teardrops no)
	)
	(paper "A4")
	(title_block
		(title "peb — Lightning_PEB_BRD.brd")
		(comment 1 "Lightning (Wiwynn / Facebook NVMe JBOF) / footprints 1044-1051 of 2563")
	)
	(layers
		(0 "F.Cu" signal "TOP")
		(4 "In1.Cu" signal "L2GND")
		(6 "In2.Cu" signal "L3")
		(8 "In3.Cu" signal "L4VCC")
		(10 "In4.Cu" signal "L5VCC")
		(12 "In5.Cu" signal "L6")
		(14 "In6.Cu" signal "L7GND")
		(2 "B.Cu" signal "BOTTOM")
		(9 "F.Adhes" user "F.Adhesive")
		(11 "B.Adhes" user "B.Adhesive")
		(13 "F.Paste" user "Package Geometry/Pastemask Top")
		(15 "B.Paste" user "Package Geometry/Pastemask Bottom")
		(5 "F.SilkS" user "Ref Des/Silkscreen Top")
		(7 "B.SilkS" user "Ref Des/Silkscreen Bottom")
		(1 "F.Mask" user "Board Geometry/Soldermask Top")
		(3 "B.Mask" user "Board Geometry/Soldermask Bottom")
		(17 "Dwgs.User" user "User.Drawings")
		(19 "Cmts.User" user "User.Comments")
		(21 "Eco1.User" user "User.Eco1")
		(23 "Eco2.User" user "User.Eco2")
		(25 "Edge.Cuts" user "Board Geometry/Outline")
		(27 "Margin" user)
		(31 "F.CrtYd" user "Package Geometry/Place Bound Top")
		(29 "B.CrtYd" user "Package Geometry/Place Bound Bottom")
		(35 "F.Fab" user "Ref Des/Assembly Top")
		(33 "B.Fab" user "Ref Des/Assembly Bottom")
	)
	(footprint ""
		(layer "F.Cu")
		(at 337.852512 -184.878218 180)
		(property "Reference" "R7960"
			(at 0 0 180)
			(layer "F.SilkS")
			(hide yes)
			(effects
				(font
					(size 1.27 1.27)
				)
			)
		)
		(property "Value" "0R2J-2-GP"
			(at 0.064008 -3.993896 180)
			(unlocked yes)
			(layer "F.Fab")
			(hide yes)
			(effects
				(font
					(size 1.016 1.016)
					(thickness 0.1524)
				)
			)
		)
		(property "Device Type" "R402H16"
			(at 0.064008 -5.517896 180)
			(unlocked yes)
			(layer "F.Fab")
			(hide yes)
			(effects
				(font
					(size 1.016 1.016)
					(thickness 0.1524)
				)
			)
		)
		(duplicate_pad_numbers_are_jumpers no)
		(fp_line
			(start 0.508 -0.9398)
			(end -0.508 -0.9398)
			(stroke
				(width 0.1524)
				(type default)
			)
			(layer "F.SilkS")
		)
		(fp_line
			(start -0.508 -0.9398)
			(end -0.508 0.9398)
			(stroke
				(width 0.1524)
				(type default)
			)
			(layer "F.SilkS")
		)
		(fp_rect
			(start -0.508 0.9398)
			(end 0.508 -0.9398)
			(stroke
				(width 0)
				(type default)
			)
			(fill no)
			(layer "F.CrtYd")
		)
		(fp_rect
			(start -0.508 0.9398)
			(end 0.508 -0.9398)
			(stroke
				(width 0)
				(type default)
			)
			(fill no)
			(layer "F.Fab")
		)
		(pad "1" smd custom
			(at 0 -0.4445 180)
			(size 0.1397 0.1397)
			(layers "F.Cu" "F.Mask" "F.Paste")
			(net "SSD_PWREN14")
			(options
				(clearance outline)
				(anchor circle)
			)
			(primitives
				(gr_poly
					(pts
						(arc
							(start -0.1778 -0.2794)
							(mid -0.249642 -0.249642)
							(end -0.2794 -0.1778)
						)
						(arc
							(start -0.2794 0.1778)
							(mid -0.249642 0.249642)
							(end -0.1778 0.2794)
						)
						(arc
							(start 0.1778 0.2794)
							(mid 0.249642 0.249642)
							(end 0.2794 0.1778)
						)
						(arc
							(start 0.2794 -0.1778)
							(mid 0.249642 -0.249642)
							(end 0.1778 -0.2794)
						)
					)
					(width 0)
					(fill yes)
				)
			)
		)
		(pad "2" smd custom
			(at 0 0.4445 180)
			(size 0.1397 0.1397)
			(layers "F.Cu" "F.Mask" "F.Paste")
			(net "SSD_PWREN14_R")
			(options
				(clearance outline)
				(anchor circle)
			)
			(primitives
				(gr_poly
					(pts
						(arc
							(start -0.1778 -0.2794)
							(mid -0.249642 -0.249642)
							(end -0.2794 -0.1778)
						)
						(arc
							(start -0.2794 0.1778)
							(mid -0.249642 0.249642)
							(end -0.1778 0.2794)
						)
						(arc
							(start 0.1778 0.2794)
							(mid 0.249642 0.249642)
							(end 0.2794 0.1778)
						)
						(arc
							(start 0.2794 -0.1778)
							(mid 0.249642 -0.249642)
							(end 0.1778 -0.2794)
						)
					)
					(width 0)
					(fill yes)
				)
			)
		)
	)
	(footprint ""
		(layer "F.Cu")
		(at 332.92288 -34.36874 -90)
		(property "Reference" "Q31"
			(at 0 0 270)
			(layer "F.SilkS")
			(hide yes)
			(effects
				(font
					(size 1.27 1.27)
				)
			)
		)
		(property "Value" "2N7002K-1-GP"
			(at 0.127 -8.9662 270)
			(unlocked yes)
			(layer "F.Fab")
			(hide yes)
			(effects
				(font
					(size 1.016 1.016)
					(thickness 0.1524)
				)
			)
		)
		(property "Device Type" "SOT23DGS2D4H44"
			(at 0.127 -10.4902 270)
			(unlocked yes)
			(layer "F.Fab")
			(hide yes)
			(effects
				(font
					(size 1.016 1.016)
					(thickness 0.1524)
				)
			)
		)
		(duplicate_pad_numbers_are_jumpers no)
		(fp_line
			(start -1.651 1.778)
			(end 1.651 1.778)
			(stroke
				(width 0.1524)
				(type default)
			)
			(layer "F.SilkS")
		)
		(fp_line
			(start 1.651 1.778)
			(end 1.651 -1.778)
			(stroke
				(width 0.1524)
				(type default)
			)
			(layer "F.SilkS")
		)
		(fp_line
			(start -1.651 -1.778)
			(end -1.651 1.778)
			(stroke
				(width 0.1524)
				(type default)
			)
			(layer "F.SilkS")
		)
		(fp_line
			(start 1.651 -1.778)
			(end -1.651 -1.778)
			(stroke
				(width 0.1524)
				(type default)
			)
			(layer "F.SilkS")
		)
		(fp_poly
			(pts
				(xy -1.778 1.8796) (xy -1.778 -1.8796) (xy 1.778 -1.8796) (xy 1.778 1.8796)
			)
			(stroke
				(width 0)
				(type default)
			)
			(fill no)
			(layer "F.CrtYd")
		)
		(fp_poly
			(pts
				(xy -1.778 1.8796) (xy -1.778 -1.8796) (xy 1.778 -1.8796) (xy 1.778 1.8796)
			)
			(stroke
				(width 0)
				(type default)
			)
			(fill no)
			(layer "F.Fab")
		)
		(pad "D" smd custom
			(at 0 -0.9525 270)
			(size 0.1905 0.1905)
			(layers "F.Cu" "F.Mask" "F.Paste")
			(net "LED_Q_6")
			(options
				(clearance outline)
				(anchor circle)
			)
			(primitives
				(gr_poly
					(pts
						(arc
							(start -0.1778 0.5715)
							(mid -0.321484 0.511984)
							(end -0.381 0.3683)
						)
						(arc
							(start -0.381 -0.3683)
							(mid -0.321484 -0.511984)
							(end -0.1778 -0.5715)
						)
						(arc
							(start 0.1778 -0.5715)
							(mid 0.321484 -0.511984)
							(end 0.381 -0.3683)
						)
						(arc
							(start 0.381 0.3683)
							(mid 0.321484 0.511984)
							(end 0.1778 0.5715)
						)
					)
					(width 0)
					(fill yes)
				)
			)
		)
		(pad "G" smd custom
			(at -0.98425 0.9525 270)
			(size 0.1905 0.1905)
			(layers "F.Cu" "F.Mask" "F.Paste")
			(net "UPLINK6_R")
			(options
				(clearance outline)
				(anchor circle)
			)
			(primitives
				(gr_poly
					(pts
						(arc
							(start -0.1778 0.5715)
							(mid -0.321484 0.511984)
							(end -0.381 0.3683)
						)
						(arc
							(start -0.381 -0.3683)
							(mid -0.321484 -0.511984)
							(end -0.1778 -0.5715)
						)
						(arc
							(start 0.1778 -0.5715)
							(mid 0.321484 -0.511984)
							(end 0.381 -0.3683)
						)
						(arc
							(start 0.381 0.3683)
							(mid 0.321484 0.511984)
							(end 0.1778 0.5715)
						)
					)
					(width 0)
					(fill yes)
				)
			)
		)
		(pad "S" smd custom
			(at 0.98425 0.9525 270)
			(size 0.1905 0.1905)
			(layers "F.Cu" "F.Mask" "F.Paste")
			(net "GND")
			(options
				(clearance outline)
				(anchor circle)
			)
			(primitives
				(gr_poly
					(pts
						(arc
							(start -0.1778 0.5715)
							(mid -0.321484 0.511984)
							(end -0.381 0.3683)
						)
						(arc
							(start -0.381 -0.3683)
							(mid -0.321484 -0.511984)
							(end -0.1778 -0.5715)
						)
						(arc
							(start 0.1778 -0.5715)
							(mid 0.321484 -0.511984)
							(end 0.381 -0.3683)
						)
						(arc
							(start 0.381 0.3683)
							(mid 0.321484 0.511984)
							(end 0.1778 0.5715)
						)
					)
					(width 0)
					(fill yes)
				)
			)
		)
	)
	(footprint ""
		(layer "F.Cu")
		(at 37.2872 -67.5894 -90)
		(property "Reference" "L7"
			(at 0 0 270)
			(layer "F.SilkS")
			(hide yes)
			(effects
				(font
					(size 1.27 1.27)
				)
			)
		)
		(property "Value" "BLM21PG300SN-2GP"
			(at 0.0254 -5.6896 270)
			(unlocked yes)
			(layer "F.Fab")
			(hide yes)
			(effects
				(font
					(size 1.016 1.016)
					(thickness 0.1524)
				)
			)
		)
		(property "Device Type" "L20125H42"
			(at 0.0254 -7.5946 270)
			(unlocked yes)
			(layer "F.Fab")
			(hide yes)
			(effects
				(font
					(size 1.016 1.016)
					(thickness 0.1524)
				)
			)
		)
		(duplicate_pad_numbers_are_jumpers no)
		(fp_line
			(start -0.9144 1.7018)
			(end 0.9144 1.7018)
			(stroke
				(width 0.1524)
				(type default)
			)
			(layer "F.SilkS")
		)
		(fp_line
			(start 0.9144 1.7018)
			(end 0.9144 -1.7018)
			(stroke
				(width 0.1524)
				(type default)
			)
			(layer "F.SilkS")
		)
		(fp_line
			(start -0.9144 -1.7018)
			(end -0.9144 1.7018)
			(stroke
				(width 0.1524)
				(type default)
			)
			(layer "F.SilkS")
		)
		(fp_line
			(start 0.9144 -1.7018)
			(end -0.9144 -1.7018)
			(stroke
				(width 0.1524)
				(type default)
			)
			(layer "F.SilkS")
		)
		(fp_rect
			(start -1.0033 1.778)
			(end 1.0033 -1.778)
			(stroke
				(width 0)
				(type default)
			)
			(fill no)
			(layer "F.CrtYd")
		)
		(fp_poly
			(pts
				(xy -1.0033 -1.778) (xy 1.0033 -1.778) (xy 1.0033 1.778) (xy -1.0033 1.778)
			)
			(stroke
				(width 0)
				(type default)
			)
			(fill no)
			(layer "F.Fab")
		)
		(pad "1" smd rect
			(at 0 -0.9652 270)
			(size 1.397 1.143)
			(layers "F.Cu" "F.Mask" "F.Paste")
			(net "P5V_STBY")
		)
		(pad "2" smd rect
			(at 0 0.9652 270)
			(size 1.397 1.143)
			(layers "F.Cu" "F.Mask" "F.Paste")
			(net "P5V_USB_BP1_F")
		)
	)
	(footprint ""
		(layer "F.Cu")
		(at 45.72 -118.364)
		(property "Reference" "TP95"
			(at 0 0 0)
			(layer "F.SilkS")
			(hide yes)
			(effects
				(font
					(size 1.27 1.27)
				)
			)
		)
		(property "Value" "TPAD28-2-GP"
			(at -0.0127 -1.6637 0)
			(unlocked yes)
			(layer "F.Fab")
			(hide yes)
			(effects
				(font
					(size 1.016 1.016)
					(thickness 0.1524)
				)
			)
		)
		(property "Device Type" "TPAD28"
			(at -0.0127 -3.1877 0)
			(unlocked yes)
			(layer "F.Fab")
			(hide yes)
			(effects
				(font
					(size 1.016 1.016)
					(thickness 0.1524)
				)
			)
		)
		(duplicate_pad_numbers_are_jumpers no)
		(fp_poly
			(pts
				(arc
					(start 0.3556 0)
					(mid -0.3556 0)
					(end 0.3556 0)
				)
			)
			(stroke
				(width 0)
				(type default)
			)
			(fill no)
			(layer "F.CrtYd")
		)
		(fp_poly
			(pts
				(arc
					(start 0.6096 0)
					(mid -0.6096 0)
					(end 0.6096 0)
				)
			)
			(stroke
				(width 0)
				(type default)
			)
			(fill no)
			(layer "F.Fab")
		)
		(pad "1" smd circle
			(at 0 0)
			(size 0.7112 0.7112)
			(layers "F.Cu" "F.Mask" "F.Paste")
			(net "TP_GPIOH6")
		)
	)
	(footprint ""
		(layer "F.Cu")
		(at 222.861124 -190.601092)
		(property "Reference" "R7980"
			(at 0 0 0)
			(layer "F.SilkS")
			(hide yes)
			(effects
				(font
					(size 1.27 1.27)
				)
			)
		)
		(property "Value" "0R2J-2-GP"
			(at 0.064008 -3.993896 0)
			(unlocked yes)
			(layer "F.Fab")
			(hide yes)
			(effects
				(font
					(size 1.016 1.016)
					(thickness 0.1524)
				)
			)
		)
		(property "Device Type" "R402H16"
			(at 0.064008 -5.517896 0)
			(unlocked yes)
			(layer "F.Fab")
			(hide yes)
			(effects
				(font
					(size 1.016 1.016)
					(thickness 0.1524)
				)
			)
		)
		(duplicate_pad_numbers_are_jumpers no)
		(fp_line
			(start -0.508 -0.9398)
			(end -0.508 0.9398)
			(stroke
				(width 0.1524)
				(type default)
			)
			(layer "F.SilkS")
		)
		(fp_line
			(start 0.508 -0.9398)
			(end -0.508 -0.9398)
			(stroke
				(width 0.1524)
				(type default)
			)
			(layer "F.SilkS")
		)
		(fp_rect
			(start -0.508 0.9398)
			(end 0.508 -0.9398)
			(stroke
				(width 0)
				(type default)
			)
			(fill no)
			(layer "F.CrtYd")
		)
		(fp_rect
			(start -0.508 0.9398)
			(end 0.508 -0.9398)
			(stroke
				(width 0)
				(type default)
			)
			(fill no)
			(layer "F.Fab")
		)
		(pad "1" smd custom
			(at 0 -0.4445)
			(size 0.1397 0.1397)
			(layers "F.Cu" "F.Mask" "F.Paste")
			(net "SSD_PERST#3")
			(options
				(clearance outline)
				(anchor circle)
			)
			(primitives
				(gr_poly
					(pts
						(arc
							(start -0.1778 -0.2794)
							(mid -0.249642 -0.249642)
							(end -0.2794 -0.1778)
						)
						(arc
							(start -0.2794 0.1778)
							(mid -0.249642 0.249642)
							(end -0.1778 0.2794)
						)
						(arc
							(start 0.1778 0.2794)
							(mid 0.249642 0.249642)
							(end 0.2794 0.1778)
						)
						(arc
							(start 0.2794 -0.1778)
							(mid 0.249642 -0.249642)
							(end 0.1778 -0.2794)
						)
					)
					(width 0)
					(fill yes)
				)
			)
		)
		(pad "2" smd custom
			(at 0 0.4445)
			(size 0.1397 0.1397)
			(layers "F.Cu" "F.Mask" "F.Paste")
			(net "SSD_PERST#3_R")
			(options
				(clearance outline)
				(anchor circle)
			)
			(primitives
				(gr_poly
					(pts
						(arc
							(start -0.1778 -0.2794)
							(mid -0.249642 -0.249642)
							(end -0.2794 -0.1778)
						)
						(arc
							(start -0.2794 0.1778)
							(mid -0.249642 0.249642)
							(end -0.1778 0.2794)
						)
						(arc
							(start 0.1778 0.2794)
							(mid 0.249642 0.249642)
							(end 0.2794 0.1778)
						)
						(arc
							(start 0.2794 -0.1778)
							(mid 0.249642 -0.249642)
							(end 0.1778 -0.2794)
						)
					)
					(width 0)
					(fill yes)
				)
			)
		)
	)
	(footprint ""
		(layer "F.Cu")
		(at 343.00795 -212.420454 180)
		(property "Reference" "C55"
			(at 0 0 180)
			(layer "F.SilkS")
			(hide yes)
			(effects
				(font
					(size 1.27 1.27)
				)
			)
		)
		(property "Value" "SCD22U10V2KX-1GP"
			(at 1.1811 -2.7051 180)
			(unlocked yes)
			(layer "F.Fab")
			(hide yes)
			(effects
				(font
					(size 1.016 1.016)
					(thickness 0.1524)
				)
			)
		)
		(property "Device Type" "C402H22"
			(at 1.1811 -4.2291 180)
			(unlocked yes)
			(layer "F.Fab")
			(hide yes)
			(effects
				(font
					(size 1.016 1.016)
					(thickness 0.1524)
				)
			)
		)
		(duplicate_pad_numbers_are_jumpers no)
		(fp_rect
			(start -0.4318 0.9525)
			(end 0.4318 -0.9525)
			(stroke
				(width 0)
				(type default)
			)
			(fill no)
			(layer "F.CrtYd")
		)
		(fp_rect
			(start -0.4318 0.9525)
			(end 0.4318 -0.9525)
			(stroke
				(width 0)
				(type default)
			)
			(fill no)
			(layer "F.Fab")
		)
		(pad "1" smd custom
			(at 0 -0.4445 180)
			(size 0.1524 0.1524)
			(layers "F.Cu" "F.Mask" "F.Paste")
			(net "PCIE_TX_CAP_N16")
			(options
				(clearance outline)
				(anchor circle)
			)
			(primitives
				(gr_poly
					(pts
						(arc
							(start 0.3048 -0.2032)
							(mid 0.275042 -0.275042)
							(end 0.2032 -0.3048)
						)
						(arc
							(start -0.2032 -0.3048)
							(mid -0.275042 -0.275042)
							(end -0.3048 -0.2032)
						)
						(arc
							(start -0.3048 0.2032)
							(mid -0.275042 0.275042)
							(end -0.2032 0.3048)
						)
						(arc
							(start 0.2032 0.3048)
							(mid 0.275042 0.275042)
							(end 0.3048 0.2032)
						)
					)
					(width 0)
					(fill yes)
				)
			)
		)
		(pad "2" smd custom
			(at 0 0.4445 180)
			(size 0.1524 0.1524)
			(layers "F.Cu" "F.Mask" "F.Paste")
			(net "PCIE_TX_N16")
			(options
				(clearance outline)
				(anchor circle)
			)
			(primitives
				(gr_poly
					(pts
						(arc
							(start 0.3048 -0.2032)
							(mid 0.275042 -0.275042)
							(end 0.2032 -0.3048)
						)
						(arc
							(start -0.2032 -0.3048)
							(mid -0.275042 -0.275042)
							(end -0.3048 -0.2032)
						)
						(arc
							(start -0.3048 0.2032)
							(mid -0.275042 0.275042)
							(end -0.2032 0.3048)
						)
						(arc
							(start 0.2032 0.3048)
							(mid 0.275042 0.275042)
							(end 0.3048 0.2032)
						)
					)
					(width 0)
					(fill yes)
				)
			)
		)
	)
	(footprint ""
		(layer "F.Cu")
		(at 131.9403 -33.54324)
		(property "Reference" "C382"
			(at 0 0 0)
			(layer "F.SilkS")
			(hide yes)
			(effects
				(font
					(size 1.27 1.27)
				)
			)
		)
		(property "Value" "SCD22U10V2KX-1GP"
			(at 1.1811 -2.7051 0)
			(unlocked yes)
			(layer "F.Fab")
			(hide yes)
			(effects
				(font
					(size 1.016 1.016)
					(thickness 0.1524)
				)
			)
		)
		(property "Device Type" "C402H22"
			(at 1.1811 -4.2291 0)
			(unlocked yes)
			(layer "F.Fab")
			(hide yes)
			(effects
				(font
					(size 1.016 1.016)
					(thickness 0.1524)
				)
			)
		)
		(duplicate_pad_numbers_are_jumpers no)
		(fp_rect
			(start -0.4318 0.9525)
			(end 0.4318 -0.9525)
			(stroke
				(width 0)
				(type default)
			)
			(fill no)
			(layer "F.CrtYd")
		)
		(fp_rect
			(start -0.4318 0.9525)
			(end 0.4318 -0.9525)
			(stroke
				(width 0)
				(type default)
			)
			(fill no)
			(layer "F.Fab")
		)
		(pad "1" smd custom
			(at 0 -0.4445)
			(size 0.1524 0.1524)
			(layers "F.Cu" "F.Mask" "F.Paste")
			(net "PCIE_TX_CAP_N81")
			(options
				(clearance outline)
				(anchor circle)
			)
			(primitives
				(gr_poly
					(pts
						(arc
							(start 0.3048 -0.2032)
							(mid 0.275042 -0.275042)
							(end 0.2032 -0.3048)
						)
						(arc
							(start -0.2032 -0.3048)
							(mid -0.275042 -0.275042)
							(end -0.3048 -0.2032)
						)
						(arc
							(start -0.3048 0.2032)
							(mid -0.275042 0.275042)
							(end -0.2032 0.3048)
						)
						(arc
							(start 0.2032 0.3048)
							(mid 0.275042 0.275042)
							(end 0.3048 0.2032)
						)
					)
					(width 0)
					(fill yes)
				)
			)
		)
		(pad "2" smd custom
			(at 0 0.4445)
			(size 0.1524 0.1524)
			(layers "F.Cu" "F.Mask" "F.Paste")
			(net "PCIE_TX_N81")
			(options
				(clearance outline)
				(anchor circle)
			)
			(primitives
				(gr_poly
					(pts
						(arc
							(start 0.3048 -0.2032)
							(mid 0.275042 -0.275042)
							(end 0.2032 -0.3048)
						)
						(arc
							(start -0.2032 -0.3048)
							(mid -0.275042 -0.275042)
							(end -0.3048 -0.2032)
						)
						(arc
							(start -0.3048 0.2032)
							(mid -0.275042 0.275042)
							(end -0.2032 0.3048)
						)
						(arc
							(start 0.2032 0.3048)
							(mid 0.275042 0.275042)
							(end 0.3048 0.2032)
						)
					)
					(width 0)
					(fill yes)
				)
			)
		)
	)
	(footprint ""
		(layer "F.Cu")
		(at 212.217 -25.527 -90)
		(property "Reference" "TP328"
			(at 0 0 270)
			(layer "F.SilkS")
			(hide yes)
			(effects
				(font
					(size 1.27 1.27)
				)
			)
		)
		(property "Value" "TPAD28-2-GP"
			(at -0.0127 -1.6637 270)
			(unlocked yes)
			(layer "F.Fab")
			(hide yes)
			(effects
				(font
					(size 1.016 1.016)
					(thickness 0.1524)
				)
			)
		)
		(property "Device Type" "TPAD28"
			(at -0.0127 -3.1877 270)
			(unlocked yes)
			(layer "F.Fab")
			(hide yes)
			(effects
				(font
					(size 1.016 1.016)
					(thickness 0.1524)
				)
			)
		)
		(duplicate_pad_numbers_are_jumpers no)
		(fp_poly
			(pts
				(arc
					(start 0 -0.3556)
					(mid 0 0.3556)
					(end 0 -0.3556)
				)
			)
			(stroke
				(width 0)
				(type default)
			)
			(fill no)
			(layer "F.CrtYd")
		)
		(fp_poly
			(pts
				(arc
					(start 0 -0.6096)
					(mid 0 0.6096)
					(end 0 -0.6096)
				)
			)
			(stroke
				(width 0)
				(type default)
			)
			(fill no)
			(layer "F.Fab")
		)
		(pad "1" smd circle
			(at 0 0 270)
			(size 0.7112 0.7112)
			(layers "F.Cu" "F.Mask" "F.Paste")
			(net "DUT_TAP_SEL")
		)
	)
)
